%FSTAX23Y23*%
%MOIN*%
%SFA1B1*%

%IPPOS*%
%ADD84R,0.314960X0.135830*%
%ADD85R,1.354330X0.230320*%
%ADD86R,0.036000X0.173000*%
%ADD87R,0.036000X0.134000*%
%ADD93R,0.065090X0.053280*%
%ADD95R,0.049340X0.051310*%
%ADD97R,0.051310X0.049340*%
%ADD134R,0.053280X0.065090*%
%ADD138R,0.090870X0.052090*%
%ADD141C,0.008000*%
%ADD142C,0.120000*%
%ADD143C,0.128000*%
%ADD144C,0.029660*%
%ADD145R,0.008000X0.008000*%
%ADD146C,0.039500*%
%ADD147C,0.073980*%
%ADD148C,0.069020*%
%ADD149R,0.069020X0.069020*%
%ADD150C,0.083000*%
%ADD151C,0.106420*%
%ADD152O,0.204850X0.106420*%
%ADD153O,0.185170X0.096580*%
%ADD154O,0.096580X0.185170*%
%ADD155C,0.063000*%
%ADD156R,0.063000X0.063000*%
%ADD157C,0.058000*%
%ADD158C,0.258000*%
%ADD159C,0.024000*%
%ADD160C,0.040000*%
%ADD161C,0.208000*%
%ADD186R,0.033200X0.034770*%
%LNtimingcard_pcb-1*%
%LPD*%
G54D84*
X0147Y00245D03*
G54D85*
X02446Y00111D03*
G54D86*
X01915Y00137D03*
X02545D03*
X02624D03*
X02899D03*
X03057D03*
X02742D03*
X02938D03*
X02781D03*
X02309D03*
X02427D03*
X02584D03*
X02072D03*
X02033D03*
X01994D03*
X01954D03*
X0219D03*
X02348D03*
X02387D03*
X02466D03*
X02505D03*
X0282D03*
X02663D03*
X0286D03*
X02978D03*
X03017D03*
X02702D03*
X02112D03*
X02151D03*
X01836D03*
X01875D03*
X03096D03*
G54D87*
X01797Y00157D03*
G54D93*
X02632Y03042D03*
Y02971D03*
G54D95*
X02341Y02854D03*
X02396D03*
G54D97*
X02712Y03043D03*
Y02988D03*
G54D134*
X02327Y02944D03*
X02398D03*
G54D138*
X02334Y03279D03*
Y032D03*
Y03121D03*
Y03042D03*
X02509Y03279D03*
Y03121D03*
Y032D03*
Y03042D03*
G54D141*
X02422Y03082D03*
Y03239D03*
Y03443D03*
Y03601D03*
G54D142*
X00199Y02481D03*
Y01956D03*
Y01431D03*
Y00906D03*
G54D143*
X00299Y02581D03*
Y02381D03*
X00099D03*
Y02581D03*
X00299Y02056D03*
Y01856D03*
X00099D03*
Y02056D03*
X00299Y01531D03*
Y01331D03*
X00099D03*
Y01531D03*
X00299Y01006D03*
Y00806D03*
X00099D03*
Y01006D03*
G54D144*
X0299Y02437D03*
X03571Y02096D03*
Y01308D03*
X02202Y02437D03*
X01696Y01308D03*
Y02096D03*
X02202Y00957D03*
X0299D03*
G54D145*
X03617Y02485D03*
X01652Y00915D03*
X01651Y02485D03*
X03617Y00915D03*
G54D146*
X03784Y04126D03*
X03958D03*
G54D147*
X02994Y04086D03*
X03294D03*
G54D148*
X05327Y01007D03*
X04327Y02307D03*
X05127Y01007D03*
X04927D03*
X04727Y02307D03*
X04927D03*
X05127D03*
X05327D03*
G54D149*
X04327Y01007D03*
G54D150*
X04298Y02595D03*
X0418D03*
X04062D03*
X03979Y0089D03*
Y02489D03*
X05578D03*
Y01689D03*
Y0089D03*
G54D151*
X05723Y03844D03*
Y04025D03*
X06569Y03806D03*
Y03589D03*
X06734Y03806D03*
Y03589D03*
X069D03*
Y03806D03*
G54D152*
X06119Y03819D03*
G54D153*
X06119Y04056D03*
G54D154*
X05934Y03937D03*
G54D155*
X02043Y04057D03*
Y04157D03*
X01457Y04053D03*
Y04153D03*
G54D156*
X02043Y04257D03*
X01457Y04253D03*
G54D157*
X06569Y04093D03*
X069D03*
G54D158*
X00285Y04152D03*
Y00368D03*
G54D159*
X02645Y0227D03*
X02618Y02299D03*
X02671Y02291D03*
X06978Y0183D03*
X02314Y00933D03*
X02413D03*
X02515D03*
X02905Y00937D03*
X02901Y01106D03*
X0285D03*
X02787D03*
X02728D03*
X02665D03*
X0261D03*
X02511Y01105D03*
X02409Y01106D03*
X02311D03*
X02322Y02429D03*
X02421D03*
X02484D03*
X02783Y02433D03*
X02874Y0229D03*
X02779Y02601D03*
X02688D03*
X0259D03*
X02488Y02574D03*
X02385Y02613D03*
X02279Y02614D03*
X03051Y02732D03*
X03414Y02892D03*
Y02736D03*
X04385Y03661D03*
X04393Y03976D03*
X04318Y03507D03*
X04116Y03597D03*
X03657Y03296D03*
X03747Y01679D03*
X03718Y01713D03*
X03712Y01673D03*
X0359Y01662D03*
X04523Y03736D03*
X0307Y03393D03*
X04438Y03354D03*
X03542Y03318D03*
X03437Y03476D03*
X03622Y03486D03*
X04437Y03661D03*
X04053Y03641D03*
X0333Y03301D03*
X03344Y02996D03*
X03342Y02263D03*
X03368Y0305D03*
X01015Y01705D03*
X01721Y01685D03*
X01003Y01177D03*
X01893Y01685D03*
X0167D03*
X03877Y03078D03*
X03799Y03201D03*
X02633Y02921D03*
X02414Y03199D03*
X02413Y03295D03*
X02591Y03186D03*
X02462Y03172D03*
X0259Y03288D03*
X02418Y03118D03*
X0522Y04086D03*
X02258Y03741D03*
X0272Y03494D03*
X06335Y03147D03*
X06262Y0322D03*
X06287Y03195D03*
X06274Y02949D03*
X06362Y02952D03*
X0645Y02462D03*
Y02535D03*
X06452Y02606D03*
X06451Y02673D03*
X0645Y0274D03*
X06587Y01529D03*
X06594Y01673D03*
Y0161D03*
Y01775D03*
Y0172D03*
X03602Y00641D03*
X02948Y02456D03*
X02252Y02613D03*
X01674Y01989D03*
X03379Y01386D03*
X03732Y01418D03*
X02579Y02281D03*
X02708Y00976D03*
X02803Y02307D03*
X02575Y02412D03*
X03719Y01996D03*
X02685Y02311D03*
X03803Y01691D03*
X02958Y02621D03*
X0245Y02282D03*
X01714Y01595D03*
X03773Y01666D03*
X02606Y00931D03*
X02881Y02566D03*
X03554Y01941D03*
X0292Y02428D03*
X03864Y01511D03*
X03404Y01363D03*
X02841Y02263D03*
X02767Y00976D03*
X0341Y01713D03*
X03414Y01805D03*
X02799Y00976D03*
X03298Y01971D03*
X02894Y02431D03*
X02759Y00795D03*
X03571Y02058D03*
X02726Y02293D03*
X0274Y00976D03*
X02826Y00795D03*
X02821Y02601D03*
X02985Y02287D03*
X02494Y02696D03*
X01822Y01674D03*
X02625Y00795D03*
X03804Y0184D03*
X02702Y02289D03*
X02893Y00795D03*
X02732D03*
X02599Y02436D03*
X01718Y01792D03*
X02475Y02291D03*
X01879Y01811D03*
X03719Y01921D03*
X03554Y01891D03*
X01568Y02067D03*
X01675Y01891D03*
X01567Y01285D03*
X02826Y00976D03*
X02394Y0272D03*
X02942Y02286D03*
X03554Y01991D03*
X03571Y02033D03*
X02692Y00795D03*
X02598D03*
X01719Y01536D03*
X02272Y02463D03*
X02681Y00976D03*
X03594Y01514D03*
X02409Y02314D03*
X03406Y01461D03*
X03392Y01871D03*
X02494Y02661D03*
X03407Y01411D03*
X02499Y02236D03*
X02409Y02283D03*
X02649Y00976D03*
X01718Y01497D03*
X01619Y02121D03*
X02622Y00976D03*
X01798Y01304D03*
X01671Y01792D03*
X02665Y00795D03*
X01671Y01399D03*
X01754Y02126D03*
X02799Y00795D03*
X03924Y01536D03*
X03549Y01441D03*
X01897Y01516D03*
X02624Y02461D03*
X03329Y01826D03*
X03719Y01766D03*
X01884Y02071D03*
X03834Y01481D03*
X0167Y01595D03*
X02862Y00795D03*
X03894Y01566D03*
X01716Y01399D03*
X03224Y01661D03*
X03379Y01336D03*
X01671Y01497D03*
X0233Y02215D03*
X03413Y01573D03*
X03197Y01714D03*
X01721Y01989D03*
Y0189D03*
X03549Y01413D03*
X03439Y0187D03*
X03252Y01661D03*
X03554Y01841D03*
X04039Y03784D03*
X02692Y02721D03*
X02511Y00405D03*
X0261Y00279D03*
X02578D03*
X0298Y00409D03*
X02821Y00407D03*
X02748Y00282D03*
X02469Y0041D03*
X02905Y00279D03*
X02878Y00249D03*
X02854Y00405D03*
X02779Y00279D03*
X02665Y00405D03*
X02704D03*
X0235D03*
X02389D03*
X02937Y00279D03*
X02957Y00251D03*
X03019Y00405D03*
X02447Y00242D03*
X02413Y00279D03*
X02444D03*
X02636Y00247D03*
X02799Y00251D03*
X02546Y00244D03*
X03097Y00251D03*
X01797Y00355D03*
X02034Y00246D03*
X01916Y00244D03*
X02309Y00246D03*
X01393Y01816D03*
X0099Y00687D03*
X04794Y02808D03*
X03183Y03135D03*
X03277Y02963D03*
X03197Y0297D03*
X03491Y03103D03*
X03188Y03187D03*
X0323Y03235D03*
X03358Y03448D03*
X02419Y02788D03*
X02146Y02753D03*
X03275Y03141D03*
X03056Y01811D03*
X02254Y03536D03*
X02579Y03486D03*
X02389Y03481D03*
X02321Y03361D03*
X02434Y03546D03*
X02634Y03406D03*
X00996Y02256D03*
X02004Y01336D03*
X02028Y01361D03*
X02549Y01755D03*
X02473Y0298D03*
X02146Y04103D03*
X02253Y04086D03*
X01408Y0398D03*
X01345Y04175D03*
X00937Y02317D03*
X02353Y04017D03*
X01726Y04329D03*
X01788D03*
X04477Y03135D03*
X04064Y02722D03*
X06628Y01372D03*
X04039Y02406D03*
X04134Y01651D03*
X03994Y01551D03*
X04134Y01751D03*
X04151Y01623D03*
X03968Y01671D03*
X03969Y01552D03*
X03944Y01816D03*
X04131Y01686D03*
X04179Y01601D03*
X04034Y01546D03*
X03996Y01711D03*
X04064Y01796D03*
Y01511D03*
X03263Y03303D03*
X0396Y02724D03*
X01569Y04171D03*
X02076Y00255D03*
Y00287D03*
X02112D03*
X02151D03*
X02112Y00255D03*
X02151D03*
X01832D03*
X01852D03*
X01872D03*
X01832Y00287D03*
X01852D03*
X01872D03*
X06647Y03129D03*
X04339Y02725D03*
X04503Y02789D03*
X03829Y03806D03*
X05577Y02214D03*
X02694Y01481D03*
X02384Y01941D03*
X0383Y03762D03*
X06334Y03266D03*
X03744Y03261D03*
X03395Y04222D03*
X04272Y03135D03*
X05634Y02236D03*
X02626Y0177D03*
X06304Y03121D03*
X03939D03*
X04208Y03135D03*
X02604Y01734D03*
X06649Y03003D03*
X04152Y03135D03*
X02299Y01916D03*
X01248Y02D03*
X02579Y0179D03*
X04068Y03135D03*
X02674Y03501D03*
X04234Y02725D03*
X06456Y03009D03*
X01691Y04079D03*
X02259Y03261D03*
X03374Y03273D03*
X06476Y03231D03*
X04333Y03135D03*
X01557Y04229D03*
X03806Y03235D03*
X01261Y02482D03*
X04114Y03135D03*
X06648Y03341D03*
X02888Y04221D03*
X01749Y0411D03*
X0257Y04283D03*
X01459Y03147D03*
X0144Y03557D03*
X01903Y04018D03*
X0229Y04217D03*
X03623Y02587D03*
X03491Y03297D03*
X03744Y03342D03*
X03394Y03447D03*
X03717Y03072D03*
X02799Y03616D03*
X03589Y01711D03*
X05733Y03556D03*
X05676Y03546D03*
X03603Y00682D03*
X02478Y00937D03*
X06694Y0183D03*
X06699Y01881D03*
X06949Y02095D03*
X06607Y02176D03*
X06395Y02111D03*
X06048Y02171D03*
X06003Y0243D03*
X06274Y02391D03*
X0491Y04203D03*
X04387Y04206D03*
X03777Y04023D03*
X04085Y03892D03*
X04194Y03884D03*
X04431Y03135D03*
X0286Y03787D03*
X02724Y03729D03*
X03531Y0366D03*
X03269Y03788D03*
X01242Y01472D03*
X01256Y00942D03*
X00654Y0079D03*
X00655Y01028D03*
X00654Y01314D03*
X00653Y01551D03*
X00654Y01839D03*
Y02073D03*
Y02365D03*
X00653Y02593D03*
X02206Y01298D03*
X02205Y032D03*
X02502Y01316D03*
X02525Y02463D03*
X03498Y02341D03*
X02429Y02621D03*
X01004Y00906D03*
X02446Y01437D03*
X01008Y0143D03*
X02409Y01967D03*
X01009Y01956D03*
X0102Y02481D03*
X02643Y01616D03*
X02666Y0164D03*
X01884Y03601D03*
X01754Y03661D03*
X03424Y03636D03*
X01549Y03621D03*
X03239Y03596D03*
X01574D03*
X03539Y03806D03*
X03219D03*
X02722Y03786D03*
X02139Y03611D03*
X02084Y03896D03*
X02083Y01411D03*
X02059Y01386D03*
Y03871D03*
X02029Y03836D03*
X01294Y04256D03*
X02004Y03816D03*
X05274Y03511D03*
X02679Y03661D03*
X02774Y03566D03*
X02993Y03751D03*
X03699D03*
X03014Y03831D03*
X03699Y03836D03*
X04254Y03776D03*
X02894Y01561D03*
X02919Y01536D03*
X02274Y01506D03*
X02719Y01591D03*
X06424Y02181D03*
X04754Y04115D03*
X01779Y04156D03*
X03504Y04086D03*
X03854Y03151D03*
X03829Y03176D03*
X06439Y03191D03*
X06354Y03331D03*
X06444Y03291D03*
X03302Y03344D03*
X06409Y03371D03*
X06447Y03396D03*
X06479Y03426D03*
X06509Y03456D03*
X03469D03*
X01849Y03701D03*
X06294D03*
G54D160*
X05964Y03555D03*
X06196Y02484D03*
X06838Y01649D03*
G54D161*
X02531Y03853D03*
Y0283D03*
X00149D03*
Y03853D03*
G54D186*
X02349Y00362D03*
Y00329D03*
X02389D03*
Y00362D03*
X02468D03*
Y00329D03*
X02511D03*
Y00362D03*
X02664Y00329D03*
Y00362D03*
X02704Y00329D03*
Y00362D03*
X02819Y00329D03*
Y00362D03*
X02854D03*
Y00329D03*
X02979D03*
Y00362D03*
X03019Y00329D03*
Y00362D03*
M02*